# SCM (Grand Teton) — schematic netlist excerpt (pin names and nets, part order shuffled) for the footprints in the layout excerpt that follows; sources: Cadence DE-HDL packaged netlist, KiCad conversion of 12092022_DA0F0TMDCD0_F0T_Management_Board_D_brd_V3_OCP.brd

U19  M24128BWDW6TP  M24128-BWDW6TP IC  pkg TSSOP8_0-65_3X4-4XG  page 26
  E0  = FRU_E0
  E1  = FRU_E1
  E2  = FRU_E2
  VSS  = GND
  SDA  = SMB_BMC_MM16_R2_SDA
  SCL  = SMB_BMC_MM16_R2_SCL
  \wc#\  = PD_FRU_WC_N
  VCC  = P3V3_AUX

R267  Q_RES  4.7K 1% EMPTY  pkg 0402LF  page 27 : A = P3V3_AUX ; B = VOL_SEN_ALERT_R

(kicad_pcb
	(version 20260206)
	(generator "pcbnew")
	(generator_version "10.0")
	(general
		(thickness 1.6)
		(legacy_teardrops no)
	)
	(paper "A4")
	(title_block
		(title "12092022_DA0F0TMDCD0_F0T_Management_Board_D_brd_V3_OCP.brd")
		(comment 1 "Grand Teton / footprints 930-931 of 1440")
	)
	(layers
		(0 "F.Cu" signal "TOP")
		(4 "In1.Cu" signal "GND")
		(6 "In2.Cu" signal "IN1")
		(8 "In3.Cu" signal "GND1")
		(10 "In4.Cu" signal "IN2")
		(12 "In5.Cu" signal "VCC")
		(14 "In6.Cu" signal "VCC1")
		(16 "In7.Cu" signal "IN3")
		(18 "In8.Cu" signal "GND2")
		(20 "In9.Cu" signal "IN4")
		(22 "In10.Cu" signal "GND3")
		(2 "B.Cu" signal "BOTTOM")
		(9 "F.Adhes" user "F.Adhesive")
		(11 "B.Adhes" user "B.Adhesive")
		(13 "F.Paste" user "Package Geometry/Pastemask Top")
		(15 "B.Paste" user "Package Geometry/Pastemask Bottom")
		(5 "F.SilkS" user "Ref Des/Silkscreen Top")
		(7 "B.SilkS" user "Ref Des/Silkscreen Bottom")
		(1 "F.Mask" user "Board Geometry/Soldermask Top")
		(3 "B.Mask" user "Board Geometry/Soldermask Bottom")
		(17 "Dwgs.User" user "User.Drawings")
		(19 "Cmts.User" user "User.Comments")
		(21 "Eco1.User" user "User.Eco1")
		(23 "Eco2.User" user "User.Eco2")
		(25 "Edge.Cuts" user "Board Geometry/Outline")
		(27 "Margin" user)
		(31 "F.CrtYd" user "Package Geometry/Place Bound Top")
		(29 "B.CrtYd" user "Package Geometry/Place Bound Bottom")
		(35 "F.Fab" user "Ref Des/Assembly Top")
		(33 "B.Fab" user "Ref Des/Assembly Bottom")
	)
	(footprint ""
		(layer "B.Cu")
		(at 75.753468 -27.159966)
		(property "Reference" "U19"
			(at 3.304032 2.307336 0)
			(unlocked yes)
			(layer "B.SilkS")
			(effects
				(font
					(size 0.7874 0.5842)
					(thickness 0.1524)
				)
				(justify left mirror)
			)
		)
		(property "Value" ""
			(at 0 0 0)
			(layer "B.Fab")
			(effects
				(font
					(size 1.27 1.27)
				)
				(justify mirror)
			)
		)
		(duplicate_pad_numbers_are_jumpers no)
		(fp_line
			(start -1.954022 -1.549908)
			(end -1.954022 1.549908)
			(stroke
				(width 0.1524)
				(type default)
			)
			(layer "B.SilkS")
		)
		(fp_line
			(start -1.954022 1.549908)
			(end 1.954022 1.549908)
			(stroke
				(width 0.1524)
				(type default)
			)
			(layer "B.SilkS")
		)
		(fp_line
			(start -0.651256 -1.549908)
			(end -1.954022 -1.549908)
			(stroke
				(width 0.1524)
				(type default)
			)
			(layer "B.SilkS")
		)
		(fp_line
			(start 0 -0.898652)
			(end -0.651256 -1.549908)
			(stroke
				(width 0.1524)
				(type default)
			)
			(layer "B.SilkS")
		)
		(fp_line
			(start 0.651256 -1.549908)
			(end 0 -0.898652)
			(stroke
				(width 0.1524)
				(type default)
			)
			(layer "B.SilkS")
		)
		(fp_line
			(start 1.954022 -1.549908)
			(end 0.651256 -1.549908)
			(stroke
				(width 0.1524)
				(type default)
			)
			(layer "B.SilkS")
		)
		(fp_line
			(start 1.954022 1.549908)
			(end 1.954022 -1.549908)
			(stroke
				(width 0.1524)
				(type default)
			)
			(layer "B.SilkS")
		)
		(fp_poly
			(pts
				(xy 5.246624 -0.403352) (xy 4.528312 0.31496) (xy 4.168902 -0.762508)
			)
			(stroke
				(width 0)
				(type default)
			)
			(fill yes)
			(layer "B.SilkS")
		)
		(fp_line
			(start -2.249932 -1.549908)
			(end 2.249932 -1.549908)
			(stroke
				(width 0.1)
				(type default)
			)
			(layer "B.Fab")
		)
		(fp_line
			(start -2.249932 1.549908)
			(end -2.249932 -1.549908)
			(stroke
				(width 0.1)
				(type default)
			)
			(layer "B.Fab")
		)
		(fp_line
			(start 2.249932 -1.549908)
			(end 2.249932 1.549908)
			(stroke
				(width 0.1)
				(type default)
			)
			(layer "B.Fab")
		)
		(fp_line
			(start 2.249932 1.549908)
			(end -2.249932 1.549908)
			(stroke
				(width 0.1)
				(type default)
			)
			(layer "B.Fab")
		)
		(fp_poly
			(pts
				(xy 5.256022 -1.483106) (xy 5.256022 -0.467106) (xy 4.240022 -0.975106)
			)
			(stroke
				(width 0)
				(type default)
			)
			(fill yes)
			(layer "B.Fab")
		)
		(pad "1" smd rect
			(at 2.970022 -0.975106 270)
			(size 0.4318 1.778)
			(layers "B.Cu" "B.Mask" "B.Paste")
			(net "FRU_E0")
		)
		(pad "2" smd rect
			(at 2.970022 -0.32512 270)
			(size 0.4318 1.778)
			(layers "B.Cu" "B.Mask" "B.Paste")
			(net "FRU_E1")
		)
		(pad "3" smd rect
			(at 2.970022 0.32512 270)
			(size 0.4318 1.778)
			(layers "B.Cu" "B.Mask" "B.Paste")
			(net "FRU_E2")
		)
		(pad "4" smd rect
			(at 2.970022 0.975106 270)
			(size 0.4318 1.778)
			(layers "B.Cu" "B.Mask" "B.Paste")
			(net "GND")
		)
		(pad "5" smd rect
			(at -2.970022 0.975106 270)
			(size 0.4318 1.778)
			(layers "B.Cu" "B.Mask" "B.Paste")
			(net "SMB_BMC_MM16_R2_SDA")
		)
		(pad "6" smd rect
			(at -2.970022 0.32512 270)
			(size 0.4318 1.778)
			(layers "B.Cu" "B.Mask" "B.Paste")
			(net "SMB_BMC_MM16_R2_SCL")
		)
		(pad "7" smd rect
			(at -2.970022 -0.32512 270)
			(size 0.4318 1.778)
			(layers "B.Cu" "B.Mask" "B.Paste")
			(net "PD_FRU_WC_N")
		)
		(pad "8" smd rect
			(at -2.970022 -0.975106 270)
			(size 0.4318 1.778)
			(layers "B.Cu" "B.Mask" "B.Paste")
			(net "P3V3_AUX")
		)
	)
	(footprint ""
		(layer "B.Cu")
		(at 39.930832 -47.137828 180)
		(property "Reference" "R267"
			(at 0 0 0)
			(layer "B.SilkS")
			(hide yes)
			(effects
				(font
					(size 1.27 1.27)
				)
				(justify mirror)
			)
		)
		(property "Value" ""
			(at 0 0 0)
			(layer "B.Fab")
			(effects
				(font
					(size 1.27 1.27)
				)
				(justify mirror)
			)
		)
		(duplicate_pad_numbers_are_jumpers no)
		(fp_line
			(start 0.7874 0.4064)
			(end 0.7874 -0.4064)
			(stroke
				(width 0.1524)
				(type default)
			)
			(layer "B.SilkS")
		)
		(fp_line
			(start 0.7874 -0.4064)
			(end -0.7874 -0.4064)
			(stroke
				(width 0.1524)
				(type default)
			)
			(layer "B.SilkS")
		)
		(fp_line
			(start -0.7874 0.4064)
			(end 0.7874 0.4064)
			(stroke
				(width 0.1524)
				(type default)
			)
			(layer "B.SilkS")
		)
		(fp_line
			(start -0.7874 -0.4064)
			(end -0.7874 0.4064)
			(stroke
				(width 0.1524)
				(type default)
			)
			(layer "B.SilkS")
		)
		(fp_line
			(start 0.67945 0.3048)
			(end 0.67945 -0.305054)
			(stroke
				(width 0.1)
				(type default)
			)
			(layer "B.Fab")
		)
		(fp_line
			(start 0.67945 -0.305054)
			(end 0.12065 -0.305054)
			(stroke
				(width 0.1)
				(type default)
			)
			(layer "B.Fab")
		)
		(fp_line
			(start 0.12065 0.3048)
			(end 0.67945 0.3048)
			(stroke
				(width 0.1)
				(type default)
			)
			(layer "B.Fab")
		)
		(fp_line
			(start 0.12065 0.2794)
			(end 0.12065 0.3048)
			(stroke
				(width 0.1)
				(type default)
			)
			(layer "B.Fab")
		)
		(fp_line
			(start 0.12065 -0.2794)
			(end -0.12065 -0.2794)
			(stroke
				(width 0.1)
				(type default)
			)
			(layer "B.Fab")
		)
		(fp_line
			(start 0.12065 -0.305054)
			(end 0.12065 -0.2794)
			(stroke
				(width 0.1)
				(type default)
			)
			(layer "B.Fab")
		)
		(fp_line
			(start -0.120396 0.3048)
			(end -0.120396 0.2794)
			(stroke
				(width 0.1)
				(type default)
			)
			(layer "B.Fab")
		)
		(fp_line
			(start -0.120396 0.2794)
			(end 0.12065 0.2794)
			(stroke
				(width 0.1)
				(type default)
			)
			(layer "B.Fab")
		)
		(fp_line
			(start -0.12065 -0.2794)
			(end -0.12065 -0.3048)
			(stroke
				(width 0.1)
				(type default)
			)
			(layer "B.Fab")
		)
		(fp_line
			(start -0.12065 -0.3048)
			(end -0.67945 -0.3048)
			(stroke
				(width 0.1)
				(type default)
			)
			(layer "B.Fab")
		)
		(fp_line
			(start -0.67945 0.3048)
			(end -0.120396 0.3048)
			(stroke
				(width 0.1)
				(type default)
			)
			(layer "B.Fab")
		)
		(fp_line
			(start -0.67945 -0.3048)
			(end -0.67945 0.3048)
			(stroke
				(width 0.1)
				(type default)
			)
			(layer "B.Fab")
		)
		(pad "1" smd circle
			(at 0.40005 0)
			(size 0 0)
			(layers "B.Cu" "B.Mask" "B.Paste")
			(net "P3V3_AUX")
		)
		(pad "2" smd circle
			(at -0.40005 0)
			(size 0 0)
			(layers "B.Cu" "B.Mask" "B.Paste")
			(net "VOL_SEN_ALERT_R")
		)
	)
)
